(kicad_pcb
	(version 20260206)
	(generator "pcbnew")
	(generator_version "10.0")
	(general
		(thickness 1.6)
		(legacy_teardrops no)
	)
	(paper "A4")
	(title_block
		(title "04192023_DAF0TMB3IC0_F0TG_MB_C_brd_V02_OCP.brd")
		(comment 1 "Grand Teton / footprints 7011-7017 of 8354")
	)
	(layers
		(0 "F.Cu" signal "TOP")
		(4 "In1.Cu" signal "GND")
		(6 "In2.Cu" signal "IN1")
		(8 "In3.Cu" signal "GND1")
		(10 "In4.Cu" signal "IN2")
		(12 "In5.Cu" signal "GND2")
		(14 "In6.Cu" signal "IN3")
		(16 "In7.Cu" signal "GND3")
		(18 "In8.Cu" signal "VCC")
		(20 "In9.Cu" signal "VCC1")
		(22 "In10.Cu" signal "GND4")
		(24 "In11.Cu" signal "IN4")
		(26 "In12.Cu" signal "GND5")
		(28 "In13.Cu" signal "IN5")
		(30 "In14.Cu" signal "GND6")
		(32 "In15.Cu" signal "IN6")
		(34 "In16.Cu" signal "GND7")
		(2 "B.Cu" signal "BOTTOM")
		(9 "F.Adhes" user "F.Adhesive")
		(11 "B.Adhes" user "B.Adhesive")
		(13 "F.Paste" user "Package Geometry/Pastemask Top")
		(15 "B.Paste" user "Package Geometry/Pastemask Bottom")
		(5 "F.SilkS" user "Ref Des/Silkscreen Top")
		(7 "B.SilkS" user "Ref Des/Silkscreen Bottom")
		(1 "F.Mask" user "Board Geometry/Soldermask Top")
		(3 "B.Mask" user "Board Geometry/Soldermask Bottom")
		(17 "Dwgs.User" user "User.Drawings")
		(19 "Cmts.User" user "User.Comments")
		(21 "Eco1.User" user "User.Eco1")
		(23 "Eco2.User" user "User.Eco2")
		(25 "Edge.Cuts" user "Board Geometry/Outline")
		(27 "Margin" user)
		(31 "F.CrtYd" user "Package Geometry/Place Bound Top")
		(29 "B.CrtYd" user "Package Geometry/Place Bound Bottom")
		(35 "F.Fab" user "Ref Des/Assembly Top")
		(33 "B.Fab" user "Ref Des/Assembly Bottom")
	)
	(footprint ""
		(layer "B.Cu")
		(at 366.62487 -176.712118 90)
		(property "Reference" "PR318"
			(at 0 0 90)
			(layer "B.SilkS")
			(hide yes)
			(effects
				(font
					(size 1.27 1.27)
				)
				(justify mirror)
			)
		)
		(property "Value" ""
			(at 0 0 90)
			(layer "B.Fab")
			(effects
				(font
					(size 1.27 1.27)
				)
				(justify mirror)
			)
		)
		(duplicate_pad_numbers_are_jumpers no)
		(fp_line
			(start 0.7874 -0.4064)
			(end -0.7874 -0.4064)
			(stroke
				(width 0.1524)
				(type default)
			)
			(layer "B.SilkS")
		)
		(fp_line
			(start -0.7874 -0.4064)
			(end -0.7874 0.4064)
			(stroke
				(width 0.1524)
				(type default)
			)
			(layer "B.SilkS")
		)
		(fp_line
			(start 0.7874 0.4064)
			(end 0.7874 -0.4064)
			(stroke
				(width 0.1524)
				(type default)
			)
			(layer "B.SilkS")
		)
		(fp_line
			(start -0.7874 0.4064)
			(end 0.7874 0.4064)
			(stroke
				(width 0.1524)
				(type default)
			)
			(layer "B.SilkS")
		)
		(fp_line
			(start 0.67945 -0.305054)
			(end 0.12065 -0.305054)
			(stroke
				(width 0.1)
				(type default)
			)
			(layer "B.Fab")
		)
		(fp_line
			(start 0.12065 -0.305054)
			(end 0.12065 -0.2794)
			(stroke
				(width 0.1)
				(type default)
			)
			(layer "B.Fab")
		)
		(fp_line
			(start -0.12065 -0.3048)
			(end -0.67945 -0.3048)
			(stroke
				(width 0.1)
				(type default)
			)
			(layer "B.Fab")
		)
		(fp_line
			(start -0.67945 -0.3048)
			(end -0.67945 0.3048)
			(stroke
				(width 0.1)
				(type default)
			)
			(layer "B.Fab")
		)
		(fp_line
			(start 0.12065 -0.2794)
			(end -0.12065 -0.2794)
			(stroke
				(width 0.1)
				(type default)
			)
			(layer "B.Fab")
		)
		(fp_line
			(start -0.12065 -0.2794)
			(end -0.12065 -0.3048)
			(stroke
				(width 0.1)
				(type default)
			)
			(layer "B.Fab")
		)
		(fp_line
			(start 0.12065 0.2794)
			(end 0.12065 0.3048)
			(stroke
				(width 0.1)
				(type default)
			)
			(layer "B.Fab")
		)
		(fp_line
			(start -0.120396 0.2794)
			(end 0.12065 0.2794)
			(stroke
				(width 0.1)
				(type default)
			)
			(layer "B.Fab")
		)
		(fp_line
			(start 0.67945 0.3048)
			(end 0.67945 -0.305054)
			(stroke
				(width 0.1)
				(type default)
			)
			(layer "B.Fab")
		)
		(fp_line
			(start 0.12065 0.3048)
			(end 0.67945 0.3048)
			(stroke
				(width 0.1)
				(type default)
			)
			(layer "B.Fab")
		)
		(fp_line
			(start -0.120396 0.3048)
			(end -0.120396 0.2794)
			(stroke
				(width 0.1)
				(type default)
			)
			(layer "B.Fab")
		)
		(fp_line
			(start -0.67945 0.3048)
			(end -0.120396 0.3048)
			(stroke
				(width 0.1)
				(type default)
			)
			(layer "B.Fab")
		)
		(pad "1" smd circle
			(at 0.40005 0 270)
			(size 0 0)
			(layers "B.Cu" "B.Mask" "B.Paste")
			(net "PVDDCR_CPU0_P0_PVCC")
		)
		(pad "2" smd circle
			(at -0.40005 0 270)
			(size 0 0)
			(layers "B.Cu" "B.Mask" "B.Paste")
			(net "PVDDCR_CPU0_P0_VCC1")
		)
	)
	(footprint ""
		(layer "B.Cu")
		(at 150.746206 -388.011162 -90)
		(property "Reference" "C403"
			(at 0 0 90)
			(layer "B.SilkS")
			(hide yes)
			(effects
				(font
					(size 1.27 1.27)
				)
				(justify mirror)
			)
		)
		(property "Value" ""
			(at 0 0 90)
			(layer "B.Fab")
			(effects
				(font
					(size 1.27 1.27)
				)
				(justify mirror)
			)
		)
		(duplicate_pad_numbers_are_jumpers no)
		(fp_line
			(start -0.299974 0.150114)
			(end 0.299974 0.150114)
			(stroke
				(width 0.1)
				(type default)
			)
			(layer "B.Fab")
		)
		(fp_line
			(start 0.299974 0.150114)
			(end 0.299974 -0.150114)
			(stroke
				(width 0.1)
				(type default)
			)
			(layer "B.Fab")
		)
		(fp_line
			(start -0.299974 -0.150114)
			(end -0.299974 0.150114)
			(stroke
				(width 0.1)
				(type default)
			)
			(layer "B.Fab")
		)
		(fp_line
			(start 0.299974 -0.150114)
			(end -0.299974 -0.150114)
			(stroke
				(width 0.1)
				(type default)
			)
			(layer "B.Fab")
		)
		(pad "1" smd rect
			(at 0.2667 0 90)
			(size 0.3048 0.381)
			(layers "B.Cu" "B.Mask" "B.Paste")
			(net "P0V9_CPU1_RT2_2A")
		)
		(pad "2" smd rect
			(at -0.2667 0 90)
			(size 0.3048 0.381)
			(layers "B.Cu" "B.Mask" "B.Paste")
			(net "GND")
		)
	)
	(footprint ""
		(layer "B.Cu")
		(at 352.974656 -169.619676 -90)
		(property "Reference" "PC572_5"
			(at 0 0 90)
			(layer "B.SilkS")
			(hide yes)
			(effects
				(font
					(size 1.27 1.27)
				)
				(justify mirror)
			)
		)
		(property "Value" ""
			(at 0 0 90)
			(layer "B.Fab")
			(effects
				(font
					(size 1.27 1.27)
				)
				(justify mirror)
			)
		)
		(duplicate_pad_numbers_are_jumpers no)
		(fp_line
			(start -1.524 0.762)
			(end 1.524 0.762)
			(stroke
				(width 0.1524)
				(type default)
			)
			(layer "B.SilkS")
		)
		(fp_line
			(start 1.524 0.762)
			(end 1.524 -0.762)
			(stroke
				(width 0.1524)
				(type default)
			)
			(layer "B.SilkS")
		)
		(fp_line
			(start -1.524 -0.762)
			(end -1.524 0.762)
			(stroke
				(width 0.1524)
				(type default)
			)
			(layer "B.SilkS")
		)
		(fp_line
			(start 1.524 -0.762)
			(end -1.524 -0.762)
			(stroke
				(width 0.1524)
				(type default)
			)
			(layer "B.SilkS")
		)
		(fp_line
			(start -1.1049 0.724916)
			(end -1.1049 -0.724916)
			(stroke
				(width 0.1)
				(type default)
			)
			(layer "B.Fab")
		)
		(fp_line
			(start 1.1049 0.724916)
			(end -1.1049 0.724916)
			(stroke
				(width 0.1)
				(type default)
			)
			(layer "B.Fab")
		)
		(fp_line
			(start -1.1049 -0.724916)
			(end 1.1049 -0.724916)
			(stroke
				(width 0.1)
				(type default)
			)
			(layer "B.Fab")
		)
		(fp_line
			(start 1.1049 -0.724916)
			(end 1.1049 0.724916)
			(stroke
				(width 0.1)
				(type default)
			)
			(layer "B.Fab")
		)
		(pad "1" smd rect
			(at 0.889 0 270)
			(size 1.016 1.27)
			(layers "B.Cu" "B.Mask" "B.Paste")
			(net "SW_P12V_AUX_PVDDCR_CPU0_P0_FLT")
		)
		(pad "2" smd rect
			(at -0.889 0 270)
			(size 1.016 1.27)
			(layers "B.Cu" "B.Mask" "B.Paste")
			(net "GND")
		)
	)
	(footprint ""
		(layer "B.Cu")
		(at 379.266958 -205.101952 -90)
		(property "Reference" "R421"
			(at 0 0 90)
			(layer "B.SilkS")
			(hide yes)
			(effects
				(font
					(size 1.27 1.27)
				)
				(justify mirror)
			)
		)
		(property "Value" ""
			(at 0 0 90)
			(layer "B.Fab")
			(effects
				(font
					(size 1.27 1.27)
				)
				(justify mirror)
			)
		)
		(duplicate_pad_numbers_are_jumpers no)
		(fp_line
			(start -0.7874 0.4064)
			(end 0.7874 0.4064)
			(stroke
				(width 0.1524)
				(type default)
			)
			(layer "B.SilkS")
		)
		(fp_line
			(start 0.7874 0.4064)
			(end 0.7874 -0.4064)
			(stroke
				(width 0.1524)
				(type default)
			)
			(layer "B.SilkS")
		)
		(fp_line
			(start -0.7874 -0.4064)
			(end -0.7874 0.4064)
			(stroke
				(width 0.1524)
				(type default)
			)
			(layer "B.SilkS")
		)
		(fp_line
			(start 0.7874 -0.4064)
			(end -0.7874 -0.4064)
			(stroke
				(width 0.1524)
				(type default)
			)
			(layer "B.SilkS")
		)
		(fp_line
			(start -0.67945 0.3048)
			(end -0.120396 0.3048)
			(stroke
				(width 0.1)
				(type default)
			)
			(layer "B.Fab")
		)
		(fp_line
			(start -0.120396 0.3048)
			(end -0.120396 0.2794)
			(stroke
				(width 0.1)
				(type default)
			)
			(layer "B.Fab")
		)
		(fp_line
			(start 0.12065 0.3048)
			(end 0.67945 0.3048)
			(stroke
				(width 0.1)
				(type default)
			)
			(layer "B.Fab")
		)
		(fp_line
			(start 0.67945 0.3048)
			(end 0.67945 -0.305054)
			(stroke
				(width 0.1)
				(type default)
			)
			(layer "B.Fab")
		)
		(fp_line
			(start -0.120396 0.2794)
			(end 0.12065 0.2794)
			(stroke
				(width 0.1)
				(type default)
			)
			(layer "B.Fab")
		)
		(fp_line
			(start 0.12065 0.2794)
			(end 0.12065 0.3048)
			(stroke
				(width 0.1)
				(type default)
			)
			(layer "B.Fab")
		)
		(fp_line
			(start -0.12065 -0.2794)
			(end -0.12065 -0.3048)
			(stroke
				(width 0.1)
				(type default)
			)
			(layer "B.Fab")
		)
		(fp_line
			(start 0.12065 -0.2794)
			(end -0.12065 -0.2794)
			(stroke
				(width 0.1)
				(type default)
			)
			(layer "B.Fab")
		)
		(fp_line
			(start -0.67945 -0.3048)
			(end -0.67945 0.3048)
			(stroke
				(width 0.1)
				(type default)
			)
			(layer "B.Fab")
		)
		(fp_line
			(start -0.12065 -0.3048)
			(end -0.67945 -0.3048)
			(stroke
				(width 0.1)
				(type default)
			)
			(layer "B.Fab")
		)
		(fp_line
			(start 0.12065 -0.305054)
			(end 0.12065 -0.2794)
			(stroke
				(width 0.1)
				(type default)
			)
			(layer "B.Fab")
		)
		(fp_line
			(start 0.67945 -0.305054)
			(end 0.12065 -0.305054)
			(stroke
				(width 0.1)
				(type default)
			)
			(layer "B.Fab")
		)
		(pad "1" smd circle
			(at 0.40005 0 90)
			(size 0 0)
			(layers "B.Cu" "B.Mask" "B.Paste")
			(net "PVDD11_S3_P0")
		)
		(pad "2" smd circle
			(at -0.40005 0 90)
			(size 0 0)
			(layers "B.Cu" "B.Mask" "B.Paste")
			(net "I3C_1_SPD_DDRGL_CPU0_R_SCL")
		)
	)
	(footprint ""
		(layer "B.Cu")
		(at 121.706386 -255.845564)
		(property "Reference" "C2457"
			(at 0 0 0)
			(layer "B.SilkS")
			(hide yes)
			(effects
				(font
					(size 1.27 1.27)
				)
				(justify mirror)
			)
		)
		(property "Value" ""
			(at 0 0 0)
			(layer "B.Fab")
			(effects
				(font
					(size 1.27 1.27)
				)
				(justify mirror)
			)
		)
		(duplicate_pad_numbers_are_jumpers no)
		(fp_line
			(start -0.7874 -0.4064)
			(end -0.7874 0.4064)
			(stroke
				(width 0.1524)
				(type default)
			)
			(layer "B.SilkS")
		)
		(fp_line
			(start -0.7874 0.4064)
			(end 0.7874 0.4064)
			(stroke
				(width 0.1524)
				(type default)
			)
			(layer "B.SilkS")
		)
		(fp_line
			(start 0.7874 -0.4064)
			(end -0.7874 -0.4064)
			(stroke
				(width 0.1524)
				(type default)
			)
			(layer "B.SilkS")
		)
		(fp_line
			(start 0.7874 0.4064)
			(end 0.7874 -0.4064)
			(stroke
				(width 0.1524)
				(type default)
			)
			(layer "B.SilkS")
		)
		(fp_line
			(start -0.67945 -0.3048)
			(end -0.67945 0.3048)
			(stroke
				(width 0.1)
				(type default)
			)
			(layer "B.Fab")
		)
		(fp_line
			(start -0.67945 0.3048)
			(end -0.120396 0.3048)
			(stroke
				(width 0.1)
				(type default)
			)
			(layer "B.Fab")
		)
		(fp_line
			(start -0.12065 -0.3048)
			(end -0.67945 -0.3048)
			(stroke
				(width 0.1)
				(type default)
			)
			(layer "B.Fab")
		)
		(fp_line
			(start -0.12065 -0.2794)
			(end -0.12065 -0.3048)
			(stroke
				(width 0.1)
				(type default)
			)
			(layer "B.Fab")
		)
		(fp_line
			(start -0.120396 0.2794)
			(end 0.12065 0.2794)
			(stroke
				(width 0.1)
				(type default)
			)
			(layer "B.Fab")
		)
		(fp_line
			(start -0.120396 0.3048)
			(end -0.120396 0.2794)
			(stroke
				(width 0.1)
				(type default)
			)
			(layer "B.Fab")
		)
		(fp_line
			(start 0.12065 -0.305054)
			(end 0.12065 -0.2794)
			(stroke
				(width 0.1)
				(type default)
			)
			(layer "B.Fab")
		)
		(fp_line
			(start 0.12065 -0.2794)
			(end -0.12065 -0.2794)
			(stroke
				(width 0.1)
				(type default)
			)
			(layer "B.Fab")
		)
		(fp_line
			(start 0.12065 0.2794)
			(end 0.12065 0.3048)
			(stroke
				(width 0.1)
				(type default)
			)
			(layer "B.Fab")
		)
		(fp_line
			(start 0.12065 0.3048)
			(end 0.67945 0.3048)
			(stroke
				(width 0.1)
				(type default)
			)
			(layer "B.Fab")
		)
		(fp_line
			(start 0.67945 -0.305054)
			(end 0.12065 -0.305054)
			(stroke
				(width 0.1)
				(type default)
			)
			(layer "B.Fab")
		)
		(fp_line
			(start 0.67945 0.3048)
			(end 0.67945 -0.305054)
			(stroke
				(width 0.1)
				(type default)
			)
			(layer "B.Fab")
		)
		(pad "1" smd circle
			(at 0.40005 0 180)
			(size 0 0)
			(layers "B.Cu" "B.Mask" "B.Paste")
			(net "PVDDCR_SOC_P1")
		)
		(pad "2" smd circle
			(at -0.40005 0 180)
			(size 0 0)
			(layers "B.Cu" "B.Mask" "B.Paste")
			(net "GND")
		)
	)
	(footprint ""
		(layer "B.Cu")
		(at 110.856014 -258.795266 180)
		(property "Reference" "C2486"
			(at 0 0 0)
			(layer "B.SilkS")
			(hide yes)
			(effects
				(font
					(size 1.27 1.27)
				)
				(justify mirror)
			)
		)
		(property "Value" ""
			(at 0 0 0)
			(layer "B.Fab")
			(effects
				(font
					(size 1.27 1.27)
				)
				(justify mirror)
			)
		)
		(duplicate_pad_numbers_are_jumpers no)
		(fp_line
			(start 0.7874 0.4064)
			(end 0.7874 -0.4064)
			(stroke
				(width 0.1524)
				(type default)
			)
			(layer "B.SilkS")
		)
		(fp_line
			(start 0.7874 -0.4064)
			(end -0.7874 -0.4064)
			(stroke
				(width 0.1524)
				(type default)
			)
			(layer "B.SilkS")
		)
		(fp_line
			(start -0.7874 0.4064)
			(end 0.7874 0.4064)
			(stroke
				(width 0.1524)
				(type default)
			)
			(layer "B.SilkS")
		)
		(fp_line
			(start -0.7874 -0.4064)
			(end -0.7874 0.4064)
			(stroke
				(width 0.1524)
				(type default)
			)
			(layer "B.SilkS")
		)
		(fp_line
			(start 0.67945 0.3048)
			(end 0.67945 -0.305054)
			(stroke
				(width 0.1)
				(type default)
			)
			(layer "B.Fab")
		)
		(fp_line
			(start 0.67945 -0.305054)
			(end 0.12065 -0.305054)
			(stroke
				(width 0.1)
				(type default)
			)
			(layer "B.Fab")
		)
		(fp_line
			(start 0.12065 0.3048)
			(end 0.67945 0.3048)
			(stroke
				(width 0.1)
				(type default)
			)
			(layer "B.Fab")
		)
		(fp_line
			(start 0.12065 0.2794)
			(end 0.12065 0.3048)
			(stroke
				(width 0.1)
				(type default)
			)
			(layer "B.Fab")
		)
		(fp_line
			(start 0.12065 -0.2794)
			(end -0.12065 -0.2794)
			(stroke
				(width 0.1)
				(type default)
			)
			(layer "B.Fab")
		)
		(fp_line
			(start 0.12065 -0.305054)
			(end 0.12065 -0.2794)
			(stroke
				(width 0.1)
				(type default)
			)
			(layer "B.Fab")
		)
		(fp_line
			(start -0.120396 0.3048)
			(end -0.120396 0.2794)
			(stroke
				(width 0.1)
				(type default)
			)
			(layer "B.Fab")
		)
		(fp_line
			(start -0.120396 0.2794)
			(end 0.12065 0.2794)
			(stroke
				(width 0.1)
				(type default)
			)
			(layer "B.Fab")
		)
		(fp_line
			(start -0.12065 -0.2794)
			(end -0.12065 -0.3048)
			(stroke
				(width 0.1)
				(type default)
			)
			(layer "B.Fab")
		)
		(fp_line
			(start -0.12065 -0.3048)
			(end -0.67945 -0.3048)
			(stroke
				(width 0.1)
				(type default)
			)
			(layer "B.Fab")
		)
		(fp_line
			(start -0.67945 0.3048)
			(end -0.120396 0.3048)
			(stroke
				(width 0.1)
				(type default)
			)
			(layer "B.Fab")
		)
		(fp_line
			(start -0.67945 -0.3048)
			(end -0.67945 0.3048)
			(stroke
				(width 0.1)
				(type default)
			)
			(layer "B.Fab")
		)
		(pad "1" smd circle
			(at 0.40005 0)
			(size 0 0)
			(layers "B.Cu" "B.Mask" "B.Paste")
			(net "PVDD11_S3_P1")
		)
		(pad "2" smd circle
			(at -0.40005 0)
			(size 0 0)
			(layers "B.Cu" "B.Mask" "B.Paste")
			(net "GND")
		)
	)
	(footprint ""
		(layer "B.Cu")
		(at 170.1292 -431.841656)
		(property "Reference" "R4127"
			(at 0 0 0)
			(layer "B.SilkS")
			(hide yes)
			(effects
				(font
					(size 1.27 1.27)
				)
				(justify mirror)
			)
		)
		(property "Value" ""
			(at 0 0 0)
			(layer "B.Fab")
			(effects
				(font
					(size 1.27 1.27)
				)
				(justify mirror)
			)
		)
		(duplicate_pad_numbers_are_jumpers no)
		(fp_line
			(start -0.7874 -0.4064)
			(end -0.7874 0.4064)
			(stroke
				(width 0.1524)
				(type default)
			)
			(layer "B.SilkS")
		)
		(fp_line
			(start -0.7874 0.4064)
			(end 0.7874 0.4064)
			(stroke
				(width 0.1524)
				(type default)
			)
			(layer "B.SilkS")
		)
		(fp_line
			(start 0.7874 -0.4064)
			(end -0.7874 -0.4064)
			(stroke
				(width 0.1524)
				(type default)
			)
			(layer "B.SilkS")
		)
		(fp_line
			(start 0.7874 0.4064)
			(end 0.7874 -0.4064)
			(stroke
				(width 0.1524)
				(type default)
			)
			(layer "B.SilkS")
		)
		(fp_line
			(start -0.67945 -0.3048)
			(end -0.67945 0.3048)
			(stroke
				(width 0.1)
				(type default)
			)
			(layer "B.Fab")
		)
		(fp_line
			(start -0.67945 0.3048)
			(end -0.120396 0.3048)
			(stroke
				(width 0.1)
				(type default)
			)
			(layer "B.Fab")
		)
		(fp_line
			(start -0.12065 -0.3048)
			(end -0.67945 -0.3048)
			(stroke
				(width 0.1)
				(type default)
			)
			(layer "B.Fab")
		)
		(fp_line
			(start -0.12065 -0.2794)
			(end -0.12065 -0.3048)
			(stroke
				(width 0.1)
				(type default)
			)
			(layer "B.Fab")
		)
		(fp_line
			(start -0.120396 0.2794)
			(end 0.12065 0.2794)
			(stroke
				(width 0.1)
				(type default)
			)
			(layer "B.Fab")
		)
		(fp_line
			(start -0.120396 0.3048)
			(end -0.120396 0.2794)
			(stroke
				(width 0.1)
				(type default)
			)
			(layer "B.Fab")
		)
		(fp_line
			(start 0.12065 -0.305054)
			(end 0.12065 -0.2794)
			(stroke
				(width 0.1)
				(type default)
			)
			(layer "B.Fab")
		)
		(fp_line
			(start 0.12065 -0.2794)
			(end -0.12065 -0.2794)
			(stroke
				(width 0.1)
				(type default)
			)
			(layer "B.Fab")
		)
		(fp_line
			(start 0.12065 0.2794)
			(end 0.12065 0.3048)
			(stroke
				(width 0.1)
				(type default)
			)
			(layer "B.Fab")
		)
		(fp_line
			(start 0.12065 0.3048)
			(end 0.67945 0.3048)
			(stroke
				(width 0.1)
				(type default)
			)
			(layer "B.Fab")
		)
		(fp_line
			(start 0.67945 -0.305054)
			(end 0.12065 -0.305054)
			(stroke
				(width 0.1)
				(type default)
			)
			(layer "B.Fab")
		)
		(fp_line
			(start 0.67945 0.3048)
			(end 0.67945 -0.305054)
			(stroke
				(width 0.1)
				(type default)
			)
			(layer "B.Fab")
		)
		(pad "1" smd circle
			(at 0.40005 0 180)
			(size 0 0)
			(layers "B.Cu" "B.Mask" "B.Paste")
			(net "P3V3_AUX")
		)
		(pad "2" smd circle
			(at -0.40005 0 180)
			(size 0 0)
			(layers "B.Cu" "B.Mask" "B.Paste")
			(net "GPU_3V3IO_RSVD1_FFU_N")
		)
	)
)
